# T6G (Grand Teton) — schematic netlist excerpt (pin names and nets, part order shuffled) for the footprints in the layout excerpt that follows; sources: Cadence DE-HDL packaged netlist, KiCad conversion of 04192023_DAF0TMB3IC0_F0TG_MB_C_brd_V02_OCP.brd

C6583  Q_CAP_DIFFBUS  DIFF BUS_0.22UF 6.3V 20% X6S  pkg C0201  page 297 : \1\ = P5E_CPU0_P2_TX_BUF_C_DP<9> ; \2\ = P5E_CPU0_P2_TX_BUF_DP<9>
R6176  Q_RES  1K 1% EMPTY  pkg 0402LF  page 112 : A = FM_P2E_BUF2_RXDET ; B = GND

(kicad_pcb
	(version 20260206)
	(generator "pcbnew")
	(generator_version "10.0")
	(general
		(thickness 1.6)
		(legacy_teardrops no)
	)
	(paper "A4")
	(title_block
		(title "04192023_DAF0TMB3IC0_F0TG_MB_C_brd_V02_OCP.brd")
		(comment 1 "Grand Teton / footprints 22-23 of 8354")
	)
	(layers
		(0 "F.Cu" signal "TOP")
		(4 "In1.Cu" signal "GND")
		(6 "In2.Cu" signal "IN1")
		(8 "In3.Cu" signal "GND1")
		(10 "In4.Cu" signal "IN2")
		(12 "In5.Cu" signal "GND2")
		(14 "In6.Cu" signal "IN3")
		(16 "In7.Cu" signal "GND3")
		(18 "In8.Cu" signal "VCC")
		(20 "In9.Cu" signal "VCC1")
		(22 "In10.Cu" signal "GND4")
		(24 "In11.Cu" signal "IN4")
		(26 "In12.Cu" signal "GND5")
		(28 "In13.Cu" signal "IN5")
		(30 "In14.Cu" signal "GND6")
		(32 "In15.Cu" signal "IN6")
		(34 "In16.Cu" signal "GND7")
		(2 "B.Cu" signal "BOTTOM")
		(9 "F.Adhes" user "F.Adhesive")
		(11 "B.Adhes" user "B.Adhesive")
		(13 "F.Paste" user "Package Geometry/Pastemask Top")
		(15 "B.Paste" user "Package Geometry/Pastemask Bottom")
		(5 "F.SilkS" user "Ref Des/Silkscreen Top")
		(7 "B.SilkS" user "Ref Des/Silkscreen Bottom")
		(1 "F.Mask" user "Board Geometry/Soldermask Top")
		(3 "B.Mask" user "Board Geometry/Soldermask Bottom")
		(17 "Dwgs.User" user "User.Drawings")
		(19 "Cmts.User" user "User.Comments")
		(21 "Eco1.User" user "User.Eco1")
		(23 "Eco2.User" user "User.Eco2")
		(25 "Edge.Cuts" user "Board Geometry/Outline")
		(27 "Margin" user)
		(31 "F.CrtYd" user "Package Geometry/Place Bound Top")
		(29 "B.CrtYd" user "Package Geometry/Place Bound Bottom")
		(35 "F.Fab" user "Ref Des/Assembly Top")
		(33 "B.Fab" user "Ref Des/Assembly Bottom")
	)
	(footprint ""
		(layer "F.Cu")
		(at 18.650458 -418.690298 -90)
		(property "Reference" "R6176"
			(at 0 0 270)
			(layer "F.SilkS")
			(hide yes)
			(effects
				(font
					(size 1.27 1.27)
				)
			)
		)
		(property "Value" ""
			(at 0 0 270)
			(layer "F.Fab")
			(effects
				(font
					(size 1.27 1.27)
				)
			)
		)
		(duplicate_pad_numbers_are_jumpers no)
		(fp_line
			(start -0.7874 0.4064)
			(end -0.7874 -0.4064)
			(stroke
				(width 0.1524)
				(type default)
			)
			(layer "F.SilkS")
		)
		(fp_line
			(start 0.7874 0.4064)
			(end -0.7874 0.4064)
			(stroke
				(width 0.1524)
				(type default)
			)
			(layer "F.SilkS")
		)
		(fp_line
			(start -0.7874 -0.4064)
			(end 0.7874 -0.4064)
			(stroke
				(width 0.1524)
				(type default)
			)
			(layer "F.SilkS")
		)
		(fp_line
			(start 0.7874 -0.4064)
			(end 0.7874 0.4064)
			(stroke
				(width 0.1524)
				(type default)
			)
			(layer "F.SilkS")
		)
		(fp_line
			(start -0.67945 0.3048)
			(end -0.67945 -0.305054)
			(stroke
				(width 0.1)
				(type default)
			)
			(layer "F.Fab")
		)
		(fp_line
			(start -0.12065 0.3048)
			(end -0.67945 0.3048)
			(stroke
				(width 0.1)
				(type default)
			)
			(layer "F.Fab")
		)
		(fp_line
			(start 0.120396 0.3048)
			(end 0.120396 0.2794)
			(stroke
				(width 0.1)
				(type default)
			)
			(layer "F.Fab")
		)
		(fp_line
			(start 0.67945 0.3048)
			(end 0.120396 0.3048)
			(stroke
				(width 0.1)
				(type default)
			)
			(layer "F.Fab")
		)
		(fp_line
			(start -0.12065 0.2794)
			(end -0.12065 0.3048)
			(stroke
				(width 0.1)
				(type default)
			)
			(layer "F.Fab")
		)
		(fp_line
			(start 0.120396 0.2794)
			(end -0.12065 0.2794)
			(stroke
				(width 0.1)
				(type default)
			)
			(layer "F.Fab")
		)
		(fp_line
			(start -0.12065 -0.2794)
			(end 0.12065 -0.2794)
			(stroke
				(width 0.1)
				(type default)
			)
			(layer "F.Fab")
		)
		(fp_line
			(start 0.12065 -0.2794)
			(end 0.12065 -0.3048)
			(stroke
				(width 0.1)
				(type default)
			)
			(layer "F.Fab")
		)
		(fp_line
			(start 0.12065 -0.3048)
			(end 0.67945 -0.3048)
			(stroke
				(width 0.1)
				(type default)
			)
			(layer "F.Fab")
		)
		(fp_line
			(start 0.67945 -0.3048)
			(end 0.67945 0.3048)
			(stroke
				(width 0.1)
				(type default)
			)
			(layer "F.Fab")
		)
		(fp_line
			(start -0.67945 -0.305054)
			(end -0.12065 -0.305054)
			(stroke
				(width 0.1)
				(type default)
			)
			(layer "F.Fab")
		)
		(fp_line
			(start -0.12065 -0.305054)
			(end -0.12065 -0.2794)
			(stroke
				(width 0.1)
				(type default)
			)
			(layer "F.Fab")
		)
		(pad "1" smd circle
			(at -0.40005 0 270)
			(size 0 0)
			(layers "F.Cu" "F.Mask" "F.Paste")
			(net "FM_P2E_BUF2_RXDET")
		)
		(pad "2" smd circle
			(at 0.40005 0 270)
			(size 0 0)
			(layers "F.Cu" "F.Mask" "F.Paste")
			(net "GND")
		)
	)
	(footprint ""
		(layer "F.Cu")
		(at 399.352262 -416.899344 -90)
		(property "Reference" "C6583"
			(at 0 0 270)
			(layer "F.SilkS")
			(hide yes)
			(effects
				(font
					(size 1.27 1.27)
				)
			)
		)
		(property "Value" ""
			(at 0 0 270)
			(layer "F.Fab")
			(effects
				(font
					(size 1.27 1.27)
				)
			)
		)
		(duplicate_pad_numbers_are_jumpers no)
		(fp_line
			(start -0.299974 0.150114)
			(end -0.299974 -0.150114)
			(stroke
				(width 0.1)
				(type default)
			)
			(layer "F.Fab")
		)
		(fp_line
			(start 0.299974 0.150114)
			(end -0.299974 0.150114)
			(stroke
				(width 0.1)
				(type default)
			)
			(layer "F.Fab")
		)
		(fp_line
			(start -0.299974 -0.150114)
			(end 0.299974 -0.150114)
			(stroke
				(width 0.1)
				(type default)
			)
			(layer "F.Fab")
		)
		(fp_line
			(start 0.299974 -0.150114)
			(end 0.299974 0.150114)
			(stroke
				(width 0.1)
				(type default)
			)
			(layer "F.Fab")
		)
		(pad "1" smd rect
			(at -0.2667 0 270)
			(size 0.3048 0.381)
			(layers "F.Cu" "F.Mask" "F.Paste")
			(net "P5E_CPU0_P2_TX_BUF_C_DP<9>")
		)
		(pad "2" smd rect
			(at 0.2667 0 270)
			(size 0.3048 0.381)
			(layers "F.Cu" "F.Mask" "F.Paste")
			(net "P5E_CPU0_P2_TX_BUF_DP<9>")
		)
	)
)
